(kicad_pcb
	(version 20241229)
	(generator "pcbnew")
	(generator_version "9.0")
	(general
		(thickness 1.552)
		(legacy_teardrops no)
	)
	(paper "A4")
	(title_block
		(date "2023-07-25")
		(rev "1.1.4")
		(comment 9 "footprints 291-293 of 379")
	)
	(layers
		(0 "F.Cu" signal)
		(4 "In1.Cu" signal)
		(6 "In2.Cu" signal)
		(8 "In3.Cu" signal)
		(10 "In4.Cu" signal)
		(12 "In5.Cu" signal)
		(14 "In6.Cu" signal)
		(2 "B.Cu" signal)
		(9 "F.Adhes" user "F.Adhesive")
		(11 "B.Adhes" user "B.Adhesive")
		(13 "F.Paste" user)
		(15 "B.Paste" user)
		(5 "F.SilkS" user "F.Silkscreen")
		(7 "B.SilkS" user "B.Silkscreen")
		(1 "F.Mask" user)
		(3 "B.Mask" user)
		(17 "Dwgs.User" user "User.Drawings")
		(19 "Cmts.User" user "User.Comments")
		(21 "Eco1.User" user "User.Eco1")
		(23 "Eco2.User" user "User.Eco2")
		(25 "Edge.Cuts" user)
		(27 "Margin" user)
		(31 "F.CrtYd" user "F.Courtyard")
		(29 "B.CrtYd" user "B.Courtyard")
		(35 "F.Fab" user)
		(33 "B.Fab" user)
	)
	(footprint "antmicro-footprints:TSSOP-14_4.4x5mm_P0.65mm"
		(layer "B.Cu")
		(at 157.53 97.15)
		(descr "TSSOP, 14 Pin (JEDEC MO-153 Var AB-1 https://www.jedec.org/document_search?search_api_views_fulltext=MO-153), generated with kicad-footprint-generator ipc_gullwing_generator.py")
		(tags "TSSOP SO")
		(property "Reference" "U3"
			(at -0.5 -3.21 0)
			(layer "B.SilkS")
			(effects
				(font
					(size 0.65 0.65)
					(thickness 0.15)
				)
				(justify right mirror)
			)
		)
		(property "Value" "LM339_TSSOP_Split"
			(at -3.8 -4.3 0)
			(layer "B.Fab")
			(hide yes)
			(effects
				(font
					(size 0.7 0.7)
					(thickness 0.15)
				)
				(justify right bottom mirror)
			)
		)
		(property "Datasheet" "https://www.ti.com/lit/ds/symlink/lm339b.pdf?ts=1679641364820&ref_url=https%253A%252F%252Fwww.google.com%252F"
			(at 0 0 0)
			(layer "F.Fab")
			(hide yes)
			(effects
				(font
					(size 1.27 1.27)
					(thickness 0.15)
				)
			)
		)
		(property "Description" "Analogue Comparator, Differential, 4 Comparators, 300 ns, 2V to 36V, TSSOP, 14 Pins"
			(at 0 0 0)
			(layer "F.Fab")
			(hide yes)
			(effects
				(font
					(size 1.27 1.27)
					(thickness 0.15)
				)
			)
		)
		(property "Author" "Antmicro"
			(at 0 0 0)
			(layer "B.Fab")
			(hide yes)
			(effects
				(font
					(size 1 1)
					(thickness 0.15)
				)
				(justify mirror)
			)
		)
		(property "License" "Apache-2.0"
			(at 0 0 0)
			(layer "B.Fab")
			(hide yes)
			(effects
				(font
					(size 1 1)
					(thickness 0.15)
				)
				(justify mirror)
			)
		)
		(property "MPN" "LM339PW"
			(at 0 0 0)
			(layer "B.Fab")
			(hide yes)
			(effects
				(font
					(size 1 1)
					(thickness 0.15)
				)
				(justify mirror)
			)
		)
		(property "Manufacturer" "Texas Instruments"
			(at 0 0 0)
			(layer "B.Fab")
			(hide yes)
			(effects
				(font
					(size 1 1)
					(thickness 0.15)
				)
				(justify mirror)
			)
		)
		(sheetname "/Power Supply/")
		(sheetfile "supply.kicad_sch")
		(attr smd)
		(fp_line
			(start -2.9 2.3)
			(end -2.3 2.3)
			(stroke
				(width 0.15)
				(type solid)
			)
			(layer "B.SilkS")
		)
		(fp_line
			(start -2.3 -2.6)
			(end -2.3 -2.3)
			(stroke
				(width 0.15)
				(type solid)
			)
			(layer "B.SilkS")
		)
		(fp_line
			(start -2.3 2.61)
			(end -2.3 2.3)
			(stroke
				(width 0.15)
				(type solid)
			)
			(layer "B.SilkS")
		)
		(fp_line
			(start -2.3 2.61)
			(end 2.3 2.605)
			(stroke
				(width 0.15)
				(type solid)
			)
			(layer "B.SilkS")
		)
		(fp_line
			(start 2.3 -2.6)
			(end -2.3 -2.6)
			(stroke
				(width 0.15)
				(type solid)
			)
			(layer "B.SilkS")
		)
		(fp_line
			(start 2.3 -2.3)
			(end 2.3 -2.6)
			(stroke
				(width 0.15)
				(type solid)
			)
			(layer "B.SilkS")
		)
		(fp_line
			(start 2.3 2.3)
			(end 2.3 2.605)
			(stroke
				(width 0.15)
				(type solid)
			)
			(layer "B.SilkS")
		)
		(fp_line
			(start -3.7 -2.6)
			(end 3.7 -2.6)
			(stroke
				(width 0.05)
				(type solid)
			)
			(layer "B.CrtYd")
		)
		(fp_line
			(start -3.7 2.6)
			(end -3.7 -2.6)
			(stroke
				(width 0.05)
				(type solid)
			)
			(layer "B.CrtYd")
		)
		(fp_line
			(start 3.7 -2.6)
			(end 3.7 2.6)
			(stroke
				(width 0.05)
				(type solid)
			)
			(layer "B.CrtYd")
		)
		(fp_line
			(start 3.7 2.6)
			(end -3.7 2.6)
			(stroke
				(width 0.05)
				(type solid)
			)
			(layer "B.CrtYd")
		)
		(fp_line
			(start -2.202 -2.499)
			(end -2.202 1.5)
			(stroke
				(width 0.15)
				(type solid)
			)
			(layer "B.Fab")
		)
		(fp_line
			(start -2.202 1.5)
			(end -1.2 2.5)
			(stroke
				(width 0.15)
				(type solid)
			)
			(layer "B.Fab")
		)
		(fp_line
			(start -1.2 2.5)
			(end 2.2 2.5)
			(stroke
				(width 0.15)
				(type solid)
			)
			(layer "B.Fab")
		)
		(fp_line
			(start 2.2 -2.499)
			(end -2.202 -2.499)
			(stroke
				(width 0.15)
				(type solid)
			)
			(layer "B.Fab")
		)
		(fp_line
			(start 2.2 2.5)
			(end 2.2 -2.499)
			(stroke
				(width 0.15)
				(type solid)
			)
			(layer "B.Fab")
		)
		(fp_text user "."
			(at -3.7 2.8 0)
			(layer "B.SilkS")
			(effects
				(font
					(size 1 1)
					(thickness 0.15)
				)
				(justify right mirror)
			)
		)
		(pad "1" smd roundrect
			(at -2.863 1.95)
			(size 1.475 0.4)
			(layers "B.Cu" "B.Mask" "B.Paste")
			(roundrect_rratio 0.25)
			(net 58 "Net-(D1-A)")
			(pintype "output")
		)
		(pad "2" smd roundrect
			(at -2.863 1.301)
			(size 1.475 0.4)
			(layers "B.Cu" "B.Mask" "B.Paste")
			(roundrect_rratio 0.25)
			(net 58 "Net-(D1-A)")
			(pintype "output")
		)
		(pad "3" smd roundrect
			(at -2.863 0.652)
			(size 1.475 0.4)
			(layers "B.Cu" "B.Mask" "B.Paste")
			(roundrect_rratio 0.25)
			(net 14 "+5V")
			(pinfunction "V+")
			(pintype "power_in")
		)
		(pad "4" smd roundrect
			(at -2.863 0)
			(size 1.475 0.4)
			(layers "B.Cu" "B.Mask" "B.Paste")
			(roundrect_rratio 0.25)
			(net 141 "/Power Supply/VREF_0V45")
			(pintype "input")
		)
		(pad "5" smd roundrect
			(at -2.863 -0.65)
			(size 1.475 0.4)
			(layers "B.Cu" "B.Mask" "B.Paste")
			(roundrect_rratio 0.25)
			(net 248 "+1V5")
			(pintype "input")
		)
		(pad "6" smd roundrect
			(at -2.863 -1.3)
			(size 1.475 0.4)
			(layers "B.Cu" "B.Mask" "B.Paste")
			(roundrect_rratio 0.25)
			(net 141 "/Power Supply/VREF_0V45")
			(pintype "input")
		)
		(pad "7" smd roundrect
			(at -2.863 -1.949)
			(size 1.475 0.4)
			(layers "B.Cu" "B.Mask" "B.Paste")
			(roundrect_rratio 0.25)
			(net 3 "+1V2")
			(pintype "input")
		)
		(pad "8" smd roundrect
			(at 2.862 -1.949)
			(size 1.475 0.4)
			(layers "B.Cu" "B.Mask" "B.Paste")
			(roundrect_rratio 0.25)
			(net 141 "/Power Supply/VREF_0V45")
			(pintype "input")
		)
		(pad "9" smd roundrect
			(at 2.862 -1.3)
			(size 1.475 0.4)
			(layers "B.Cu" "B.Mask" "B.Paste")
			(roundrect_rratio 0.25)
			(net 6 "Vtt")
			(pintype "input")
		)
		(pad "10" smd roundrect
			(at 2.862 -0.65)
			(size 1.475 0.4)
			(layers "B.Cu" "B.Mask" "B.Paste")
			(roundrect_rratio 0.25)
			(net 1 "GND")
			(pintype "input")
		)
		(pad "11" smd roundrect
			(at 2.862 0)
			(size 1.475 0.4)
			(layers "B.Cu" "B.Mask" "B.Paste")
			(roundrect_rratio 0.25)
			(net 14 "+5V")
			(pintype "input")
		)
		(pad "12" smd roundrect
			(at 2.862 0.652)
			(size 1.475 0.4)
			(layers "B.Cu" "B.Mask" "B.Paste")
			(roundrect_rratio 0.25)
			(net 1 "GND")
			(pinfunction "V-")
			(pintype "power_in")
		)
		(pad "13" smd roundrect
			(at 2.862 1.301)
			(size 1.475 0.4)
			(layers "B.Cu" "B.Mask" "B.Paste")
			(roundrect_rratio 0.25)
			(net 174 "unconnected-(U3-Pad13)")
			(pintype "output+no_connect")
		)
		(pad "14" smd roundrect
			(at 2.862 1.95)
			(size 1.475 0.4)
			(layers "B.Cu" "B.Mask" "B.Paste")
			(roundrect_rratio 0.25)
			(net 58 "Net-(D1-A)")
			(pintype "output")
		)
	)
	(footprint "antmicro-footprints:QFN-16-1EP_4x4mm_P0.65mm"
		(layer "B.Cu")
		(at 145.75 85.25)
		(property "Reference" "U20"
			(at -0.07 3.19 180)
			(layer "B.SilkS")
			(effects
				(font
					(size 0.7 0.7)
					(thickness 0.15)
				)
				(justify left bottom mirror)
			)
		)
		(property "Value" "FT230X_QFN"
			(at 0 -3.3 180)
			(layer "B.Fab")
			(effects
				(font
					(size 0.7 0.7)
					(thickness 0.15)
				)
				(justify left bottom mirror)
			)
		)
		(property "Datasheet" "https://ftdichip.com/wp-content/uploads/2021/10/DS_FT230X.pdf"
			(at 0 0 0)
			(layer "F.Fab")
			(hide yes)
			(effects
				(font
					(size 1.27 1.27)
					(thickness 0.15)
				)
			)
		)
		(property "Description" "USB Interface, USB-UART Converter, USB 2.0, 2.97 V, 5.5 V, QFN, 16 Pins"
			(at 0 0 0)
			(layer "F.Fab")
			(hide yes)
			(effects
				(font
					(size 1.27 1.27)
					(thickness 0.15)
				)
			)
		)
		(property "Author" "Antmicro"
			(at 0 0 0)
			(layer "B.Fab")
			(hide yes)
			(effects
				(font
					(size 1 1)
					(thickness 0.15)
				)
				(justify mirror)
			)
		)
		(property "License" "Apache-2.0"
			(at 0 0 0)
			(layer "B.Fab")
			(hide yes)
			(effects
				(font
					(size 1 1)
					(thickness 0.15)
				)
				(justify mirror)
			)
		)
		(property "MPN" "FT230XQ-R"
			(at 0 0 0)
			(layer "B.Fab")
			(hide yes)
			(effects
				(font
					(size 1 1)
					(thickness 0.15)
				)
				(justify mirror)
			)
		)
		(property "Manufacturer" "FTDI Chip"
			(at 0 0 0)
			(layer "B.Fab")
			(hide yes)
			(effects
				(font
					(size 1 1)
					(thickness 0.15)
				)
				(justify mirror)
			)
		)
		(sheetname "/Peripherals/")
		(sheetfile "peripherals.kicad_sch")
		(attr smd)
		(fp_line
			(start -2.101 -2.1)
			(end -1.5 -2.1)
			(stroke
				(width 0.15)
				(type solid)
			)
			(layer "B.SilkS")
		)
		(fp_line
			(start -2.101 -1.398)
			(end -2.101 -2.1)
			(stroke
				(width 0.15)
				(type solid)
			)
			(layer "B.SilkS")
		)
		(fp_line
			(start -2.1 2.1)
			(end -2.101 1.4)
			(stroke
				(width 0.15)
				(type solid)
			)
			(layer "B.SilkS")
		)
		(fp_line
			(start -1.4 2.1)
			(end -2.1 2.1)
			(stroke
				(width 0.15)
				(type solid)
			)
			(layer "B.SilkS")
		)
		(fp_line
			(start 1.499 -2.1)
			(end 2.1 -2.1)
			(stroke
				(width 0.15)
				(type solid)
			)
			(layer "B.SilkS")
		)
		(fp_line
			(start 1.499 2.101)
			(end 2.1 2.101)
			(stroke
				(width 0.15)
				(type solid)
			)
			(layer "B.SilkS")
		)
		(fp_line
			(start 2.1 -2.1)
			(end 2.1 -1.398)
			(stroke
				(width 0.15)
				(type solid)
			)
			(layer "B.SilkS")
		)
		(fp_line
			(start 2.1 2.101)
			(end 2.1 1.401)
			(stroke
				(width 0.15)
				(type solid)
			)
			(layer "B.SilkS")
		)
		(fp_circle
			(center -2.35 1.4)
			(end -2.3 1.4)
			(stroke
				(width 0.15)
				(type solid)
			)
			(fill yes)
			(layer "B.SilkS")
		)
		(fp_rect
			(start -2.35 2.35)
			(end 2.35 -2.35)
			(stroke
				(width 0.05)
				(type solid)
			)
			(fill no)
			(layer "B.CrtYd")
		)
		(fp_line
			(start -1.5 2)
			(end -2 1.5)
			(stroke
				(width 0.15)
				(type solid)
			)
			(layer "B.Fab")
		)
		(fp_rect
			(start 2 -2)
			(end -2 2)
			(stroke
				(width 0.15)
				(type solid)
			)
			(fill no)
			(layer "B.Fab")
		)
		(fp_text user "Author: Antmicro"
			(at -2.35 -6.799 180)
			(layer "B.Fab")
			(effects
				(font
					(size 0.7 0.7)
					(thickness 0.15)
				)
				(justify left bottom mirror)
			)
		)
		(fp_text user "${REFERENCE}"
			(at -2.35 -5.599 180)
			(layer "B.Fab")
			(effects
				(font
					(size 0.7 0.7)
					(thickness 0.15)
				)
				(justify left bottom mirror)
			)
		)
		(fp_text user "License: Apache-2.0"
			(at -2.35 -7.999 180)
			(layer "B.Fab")
			(effects
				(font
					(size 0.7 0.7)
					(thickness 0.15)
				)
				(justify left bottom mirror)
			)
		)
		(pad "1" smd rect
			(at -1.9 0.975)
			(size 0.8 0.4)
			(layers "B.Cu" "B.Mask" "B.Paste")
			(net 348 "/Peripherals/FTDI_VCCIO")
			(pinfunction "V_{CCIO}")
			(pintype "power_in")
		)
		(pad "2" smd rect
			(at -1.9 0.325)
			(size 0.8 0.4)
			(layers "B.Cu" "B.Mask" "B.Paste")
			(net 355 "RXD")
			(pinfunction "RXD")
			(pintype "input")
		)
		(pad "3" smd rect
			(at -1.9 -0.325)
			(size 0.8 0.4)
			(layers "B.Cu" "B.Mask" "B.Paste")
			(net 1 "GND")
			(pinfunction "GND")
			(pintype "passive")
		)
		(pad "4" smd rect
			(at -1.9 -0.975)
			(size 0.8 0.4)
			(layers "B.Cu" "B.Mask" "B.Paste")
			(net 396 "unconnected-(U20-~{CTS}-Pad4)")
			(pinfunction "~{CTS}")
			(pintype "input+no_connect")
		)
		(pad "5" smd rect
			(at -0.975 -1.9)
			(size 0.4 0.8)
			(layers "B.Cu" "B.Mask" "B.Paste")
			(net 296 "Net-(D13-C)")
			(pinfunction "CBUS2")
			(pintype "bidirectional")
		)
		(pad "6" smd rect
			(at -0.325 -1.9)
			(size 0.4 0.8)
			(layers "B.Cu" "B.Mask" "B.Paste")
			(net 362 "/Peripherals/USB_D2P")
			(pinfunction "D+")
			(pintype "input")
		)
		(pad "7" smd rect
			(at 0.325 -1.9)
			(size 0.4 0.8)
			(layers "B.Cu" "B.Mask" "B.Paste")
			(net 361 "/Peripherals/USB_D2N")
			(pinfunction "D-")
			(pintype "input")
		)
		(pad "8" smd rect
			(at 0.975 -1.9)
			(size 0.4 0.8)
			(layers "B.Cu" "B.Mask" "B.Paste")
			(net 348 "/Peripherals/FTDI_VCCIO")
			(pinfunction "3V3_{OUT}")
			(pintype "passive")
		)
		(pad "9" smd rect
			(at 1.9 -0.975)
			(size 0.8 0.4)
			(layers "B.Cu" "B.Mask" "B.Paste")
			(net 348 "/Peripherals/FTDI_VCCIO")
			(pinfunction "~{RESET}")
			(pintype "input")
		)
		(pad "10" smd rect
			(at 1.9 -0.325)
			(size 0.8 0.4)
			(layers "B.Cu" "B.Mask" "B.Paste")
			(net 325 "USB_POWER_IN")
			(pinfunction "V_{CC}")
			(pintype "power_in")
		)
		(pad "11" smd rect
			(at 1.9 0.325)
			(size 0.8 0.4)
			(layers "B.Cu" "B.Mask" "B.Paste")
			(net 258 "Net-(D12-C)")
			(pinfunction "CBUS1")
			(pintype "bidirectional")
		)
		(pad "12" smd rect
			(at 1.9 0.975)
			(size 0.8 0.4)
			(layers "B.Cu" "B.Mask" "B.Paste")
			(net 379 "Net-(U20-CBUS0)")
			(pinfunction "CBUS0")
			(pintype "bidirectional")
		)
		(pad "13" smd rect
			(at 0.975 1.9)
			(size 0.4 0.8)
			(layers "B.Cu" "B.Mask" "B.Paste")
			(net 1 "GND")
			(pinfunction "GND")
			(pintype "power_in")
		)
		(pad "14" smd rect
			(at 0.325 1.9)
			(size 0.4 0.8)
			(layers "B.Cu" "B.Mask" "B.Paste")
			(net 380 "Net-(U20-CBUS3)")
			(pinfunction "CBUS3")
			(pintype "bidirectional")
		)
		(pad "15" smd rect
			(at -0.325 1.9)
			(size 0.4 0.8)
			(layers "B.Cu" "B.Mask" "B.Paste")
			(net 357 "TXD")
			(pinfunction "TXD")
			(pintype "output")
		)
		(pad "16" smd rect
			(at -0.975 1.9)
			(size 0.4 0.8)
			(layers "B.Cu" "B.Mask" "B.Paste")
			(net 397 "unconnected-(U20-~{RTS}-Pad16)")
			(pinfunction "~{RTS}")
			(pintype "output+no_connect")
		)
		(pad "17" smd rect
			(at 0 0)
			(size 2.3 2.3)
			(layers "B.Cu" "B.Mask" "B.Paste")
			(net 1 "GND")
			(pinfunction "GND")
			(pintype "passive")
		)
	)
	(footprint "antmicro-footprints:C_0201"
		(layer "B.Cu")
		(at 130.7 95.59 180)
		(descr "Capacitor SMD 0201")
		(tags "capacitor SMD 0201")
		(property "Reference" "C101"
			(at 8.07 12.185736 180)
			(layer "B.SilkS")
			(effects
				(font
					(size 0.65 0.65)
					(thickness 0.15)
				)
				(justify left bottom mirror)
			)
		)
		(property "Value" "C_100n_0201"
			(at 0 -1.4 0)
			(layer "B.Fab")
			(hide yes)
			(effects
				(font
					(size 0.7 0.7)
					(thickness 0.15)
				)
				(justify left bottom mirror)
			)
		)
		(property "Datasheet" "https://www.yageo.com/en/Chart/Download/pdf/CC0201KRX6S5BB104"
			(at 0 0 180)
			(layer "F.Fab")
			(hide yes)
			(effects
				(font
					(size 1.27 1.27)
					(thickness 0.15)
				)
			)
		)
		(property "Description" "SMD Multilayer Ceramic Capacitor, 0.1 µF, 6.3 V, 0201 [0603 Metric], ± 10%, X6S, CC Series"
			(at 0 0 180)
			(layer "F.Fab")
			(hide yes)
			(effects
				(font
					(size 1.27 1.27)
					(thickness 0.15)
				)
			)
		)
		(property "Author" "Antmicro"
			(at 261.4 191.18 0)
			(layer "B.Fab")
			(hide yes)
			(effects
				(font
					(size 1 1)
					(thickness 0.15)
				)
				(justify mirror)
			)
		)
		(property "Dielectric" ""
			(at 261.4 191.18 0)
			(layer "B.Fab")
			(hide yes)
			(effects
				(font
					(size 1 1)
					(thickness 0.15)
				)
				(justify mirror)
			)
		)
		(property "License" "Apache-2.0"
			(at 261.4 191.18 0)
			(layer "B.Fab")
			(hide yes)
			(effects
				(font
					(size 1 1)
					(thickness 0.15)
				)
				(justify mirror)
			)
		)
		(property "MPN" "CC0201KRX6S5BB104"
			(at 261.4 191.18 0)
			(layer "B.Fab")
			(hide yes)
			(effects
				(font
					(size 1 1)
					(thickness 0.15)
				)
				(justify mirror)
			)
		)
		(property "Manufacturer" "YAGEO"
			(at 261.4 191.18 0)
			(layer "B.Fab")
			(hide yes)
			(effects
				(font
					(size 1 1)
					(thickness 0.15)
				)
				(justify mirror)
			)
		)
		(property "Val" "100n"
			(at 261.4 191.18 0)
			(layer "B.Fab")
			(hide yes)
			(effects
				(font
					(size 1 1)
					(thickness 0.15)
				)
				(justify mirror)
			)
		)
		(property "Voltage" ""
			(at 261.4 191.18 0)
			(layer "B.Fab")
			(hide yes)
			(effects
				(font
					(size 1 1)
					(thickness 0.15)
				)
				(justify mirror)
			)
		)
		(property "Public" "False"
			(at 0 0 180)
			(unlocked yes)
			(layer "B.Fab")
			(hide yes)
			(effects
				(font
					(size 1 1)
					(thickness 0.15)
				)
				(justify mirror)
			)
		)
		(sheetname "/FPGA Power/")
		(sheetfile "FPGA_Power.kicad_sch")
		(attr smd)
		(fp_rect
			(start -0.7 0.35)
			(end 0.7 -0.35)
			(stroke
				(width 0.05)
				(type default)
			)
			(fill no)
			(layer "B.CrtYd")
		)
		(fp_rect
			(start 0.3 -0.15)
			(end -0.301 0.149)
			(stroke
				(width 0.15)
				(type solid)
			)
			(fill no)
			(layer "B.Fab")
		)
		(fp_text user "Author: Antmicro"
			(at -0.72 -5.4 0)
			(layer "B.Fab")
			(effects
				(font
					(size 0.7 0.7)
					(thickness 0.15)
				)
				(justify left bottom mirror)
			)
		)
		(fp_text user "License: Apache-2.0"
			(at -0.72 -4.4 0)
			(layer "B.Fab")
			(effects
				(font
					(size 0.7 0.7)
					(thickness 0.15)
				)
				(justify left bottom mirror)
			)
		)
		(fp_text user "${REFERENCE}"
			(at -0.72 -3.4 0)
			(layer "B.Fab")
			(effects
				(font
					(size 0.7 0.7)
					(thickness 0.15)
				)
				(justify left bottom mirror)
			)
		)
		(pad "" smd roundrect
			(at -0.349 0.002 180)
			(size 0.318 0.36)
			(layers "B.Paste")
			(roundrect_rratio 0.25)
		)
		(pad "" smd roundrect
			(at 0.341 0.002 180)
			(size 0.318 0.36)
			(layers "B.Paste")
			(roundrect_rratio 0.25)
		)
		(pad "1" smd roundrect
			(at -0.321 0.002 180)
			(size 0.46 0.4)
			(layers "B.Cu" "B.Mask")
			(roundrect_rratio 0.25)
			(net 1 "GND")
			(pintype "passive")
		)
		(pad "2" smd roundrect
			(at 0.32 0.002 180)
			(size 0.46 0.4)
			(layers "B.Cu" "B.Mask")
			(roundrect_rratio 0.25)
			(net 11 "/FPGA Power/VCC_DPHY")
			(pintype "passive")
		)
	)
)
